G04 ================== begin FILE IDENTIFICATION RECORD ==================*
G04 Layout Name:  12433-2a.brd*
G04 Film Name:    WSILK_T*
G04 File Format:  Gerber RS274X*
G04 File Origin:  Cadence Allegro 16.5-S056*
G04 Origin Date:  Fri Dec 11 16:47:38 2015*
G04 *
G04 Layer:  DRAWING FORMAT/LAYER_WSILK_T*
G04 Layer:  DRAWING FORMAT/LAYER_PCB_STORY*
G04 Layer:  BOARD GEOMETRY/WSILK_T*
G04 Layer:  BOARD GEOMETRY/PANEL_OUTLINE*
G04 *
G04 Offset:    (0.00 0.00)*
G04 Mirror:    No*
G04 Mode:      Positive*
G04 Rotation:  0*
G04 FullContactRelief:  No*
G04 UndefLineWidth:     6.00*
G04 ================== end FILE IDENTIFICATION RECORD ====================*
%FSLAX35Y35*MOIN*%
%IR0*IPPOS*OFA0.00000B0.00000*MIA0B0*SFA1.00000B1.00000*%
%ADD10C,.02*%
%ADD11C,.025*%
%ADD12C,.005*%
%ADD13C,.006*%
%ADD14C,.008*%
G75*
%LPD*%
G75*
G54D10*
G01X-448201Y-66763D02*
X-480201D01*
G01X-448201Y-82763D02*
Y-162763D01*
G01Y-118263D02*
X752899D01*
G01X-448201Y-162763D02*
X752899D01*
G01X-452201Y-66763D02*
G02I-12000J0D01*
G01X-457351D02*
G02I-6850J0D01*
G01X-464201Y-82763D02*
Y-50763D01*
G01X-448201Y-82763D02*
X752899D01*
G01X-34601D02*
Y-162763D01*
G01X102899Y-82763D02*
Y-162763D01*
G01X217899Y-82763D02*
Y-162763D01*
G01X385399Y-82763D02*
Y-162763D01*
G01X555399Y-82763D02*
Y-162763D01*
G01X752899Y-82763D02*
Y-162763D01*
G01X780899Y-66763D02*
G02I-12000J0D01*
G01X775749D02*
G02I-6850J0D01*
G01X768899Y-82763D02*
Y-50763D01*
G01X784899Y-66763D02*
X752899D01*
G54D11*
G01X109500Y1633500D02*
X91500D01*
Y1640700D01*
X92400Y1643100D01*
X94500Y1644900D01*
X96900Y1645500D01*
X99300Y1644900D01*
X101100Y1643400D01*
X102001Y1640700D01*
Y1633500D01*
G01X91500Y1649100D02*
X109500Y1653300D01*
X91500Y1658100D01*
X109500Y1662900D01*
X91500Y1667100D01*
G01X109500Y1670700D02*
X91500D01*
Y1678200D01*
X92400Y1680600D01*
X93600Y1682100D01*
X96000Y1682700D01*
X98400Y1682100D01*
X99900Y1680300D01*
X100800Y1678200D01*
Y1670700D01*
G01Y1678200D02*
X109500Y1682700D01*
G01X161500Y1641800D02*
Y1647800D01*
X166900D01*
X168700Y1646000D01*
X169900Y1643900D01*
X170500Y1640900D01*
X169900Y1637900D01*
X168700Y1635800D01*
X166900Y1634000D01*
X164800Y1632800D01*
X162400Y1632200D01*
X160300D01*
X158500Y1632800D01*
X156400Y1634000D01*
X154600Y1635800D01*
X153400Y1637600D01*
X152500Y1640000D01*
Y1642100D01*
X153100Y1644500D01*
X154300Y1646300D01*
G01X170500Y1651700D02*
X152500D01*
X170500Y1665500D01*
X152500D01*
G01X170500Y1670600D02*
X152500D01*
Y1676600D01*
X153400Y1679000D01*
X154600Y1680800D01*
X156400Y1682300D01*
X158500Y1683500D01*
X161500Y1683800D01*
X164500Y1683500D01*
X166600Y1682300D01*
X168400Y1680800D01*
X169600Y1679000D01*
X170500Y1676600D01*
Y1670600D01*
G54D12*
G01X55200Y301233D02*
X58067D01*
X58667Y301500D01*
X59067Y302033D01*
X59200Y302700D01*
X59067Y303367D01*
X58667Y303900D01*
X58067Y304167D01*
X55200D01*
G01X59200Y305867D02*
X55200D01*
Y307467D01*
X55400Y308000D01*
X55867Y308400D01*
X56400Y308533D01*
X56933Y308400D01*
X57333Y308067D01*
X57533Y307467D01*
Y305867D01*
G01X59200Y310367D02*
X55200D01*
Y311967D01*
X55400Y312500D01*
X55867Y312900D01*
X56400Y313033D01*
X56933Y312900D01*
X57333Y312567D01*
X57533Y311967D01*
Y310367D01*
G01X59200Y317533D02*
Y314867D01*
X55200D01*
Y317533D01*
G01X57133Y316467D02*
Y314867D01*
G01X59200Y319367D02*
X55200D01*
Y321033D01*
X55400Y321567D01*
X55667Y321900D01*
X56200Y322033D01*
X56733Y321900D01*
X57067Y321500D01*
X57267Y321033D01*
Y319367D01*
G01Y321033D02*
X59200Y322033D01*
G01X55200Y329700D02*
X59200D01*
G01X55200Y328167D02*
Y331233D01*
G01X59200Y332867D02*
X55200D01*
Y334533D01*
X55400Y335067D01*
X55667Y335400D01*
X56200Y335533D01*
X56733Y335400D01*
X57067Y335000D01*
X57267Y334533D01*
Y332867D01*
G01Y334533D02*
X59200Y335533D01*
G01Y337033D02*
X55200Y338700D01*
X59200Y340367D01*
G01X57800Y339767D02*
Y337633D01*
G01X59200Y343200D02*
X57400D01*
X55200Y341867D01*
G01Y344533D02*
X57400Y343200D01*
G01X198500Y300167D02*
X202500D01*
Y302833D01*
G01Y306000D02*
X202433Y305467D01*
X202167Y305000D01*
X201767Y304600D01*
X201300Y304333D01*
X200767Y304200D01*
X200233D01*
X199700Y304333D01*
X199233Y304600D01*
X198833Y305000D01*
X198567Y305467D01*
X198500Y306000D01*
X198567Y306533D01*
X198833Y307000D01*
X199233Y307400D01*
X199700Y307667D01*
X200233Y307800D01*
X200767D01*
X201300Y307667D01*
X201767Y307400D01*
X202167Y307000D01*
X202433Y306533D01*
X202500Y306000D01*
G01X198500Y308500D02*
X202500Y309433D01*
X198500Y310500D01*
X202500Y311567D01*
X198500Y312500D01*
G01X202500Y316333D02*
Y313667D01*
X198500D01*
Y316333D01*
G01X200433Y315267D02*
Y313667D01*
G01X202500Y318167D02*
X198500D01*
Y319833D01*
X198700Y320367D01*
X198967Y320700D01*
X199500Y320833D01*
X200033Y320700D01*
X200367Y320300D01*
X200567Y319833D01*
Y318167D01*
G01Y319833D02*
X202500Y320833D01*
G01X198500Y328500D02*
X202500D01*
G01X198500Y326967D02*
Y330033D01*
G01X202500Y331667D02*
X198500D01*
Y333333D01*
X198700Y333867D01*
X198967Y334200D01*
X199500Y334333D01*
X200033Y334200D01*
X200367Y333800D01*
X200567Y333333D01*
Y331667D01*
G01Y333333D02*
X202500Y334333D01*
G01Y335833D02*
X198500Y337500D01*
X202500Y339167D01*
G01X201100Y338567D02*
Y336433D01*
G01X202500Y342000D02*
X200700D01*
X198500Y340667D01*
G01Y343333D02*
X200700Y342000D01*
G54D13*
G01X-430254Y-152763D02*
Y-135263D01*
G01X-421958D02*
X-430254Y-146055D01*
G01X-420648Y-152763D02*
X-426543Y-141097D01*
G01X-412973Y-152763D02*
Y-135263D01*
X-402929Y-152763D01*
Y-135263D01*
G01X-390451Y-152763D02*
X-392198Y-152471D01*
X-393726Y-151305D01*
X-395036Y-149555D01*
X-395910Y-147513D01*
X-396346Y-145180D01*
Y-142846D01*
X-395910Y-140513D01*
X-395036Y-138471D01*
X-393726Y-136722D01*
X-392198Y-135555D01*
X-390451Y-135263D01*
X-388705Y-135555D01*
X-387176Y-136722D01*
X-385866Y-138471D01*
X-384992Y-140513D01*
X-384556Y-142846D01*
Y-145180D01*
X-384992Y-147513D01*
X-385866Y-149555D01*
X-387176Y-151305D01*
X-388705Y-152471D01*
X-390451Y-152763D01*
G01X-377536D02*
X-368366Y-135263D01*
G01X-377536D02*
X-368366Y-152763D01*
G01X-362001Y-158596D02*
X-348901D01*
G01X-342099Y-152763D02*
Y-135263D01*
X-333803D01*
G01X-336859Y-143721D02*
X-342099D01*
G01X-325910Y-152763D02*
X-320451Y-135263D01*
X-314992Y-152763D01*
G01X-316958Y-146638D02*
X-323945D01*
G01X-307973Y-152763D02*
Y-135263D01*
X-297929Y-152763D01*
Y-135263D01*
G01X-263148Y-136722D02*
X-264458Y-135846D01*
X-265986Y-135263D01*
X-267733D01*
X-269698Y-136138D01*
X-271226Y-137596D01*
X-272318Y-139347D01*
X-273191Y-142263D01*
X-273410Y-144888D01*
X-272973Y-147513D01*
X-272318Y-149263D01*
X-271008Y-151013D01*
X-269479Y-152180D01*
X-267951Y-152763D01*
X-266423D01*
X-264894Y-152180D01*
X-263584Y-151305D01*
X-262492Y-150139D01*
G01X-250451Y-152763D02*
X-252198Y-152471D01*
X-253726Y-151305D01*
X-255036Y-149555D01*
X-255910Y-147513D01*
X-256346Y-145180D01*
Y-142846D01*
X-255910Y-140513D01*
X-255036Y-138471D01*
X-253726Y-136722D01*
X-252198Y-135555D01*
X-250451Y-135263D01*
X-248705Y-135555D01*
X-247176Y-136722D01*
X-245866Y-138471D01*
X-244992Y-140513D01*
X-244556Y-142846D01*
Y-145180D01*
X-244992Y-147513D01*
X-245866Y-149555D01*
X-247176Y-151305D01*
X-248705Y-152471D01*
X-250451Y-152763D01*
G01X-237973D02*
Y-135263D01*
X-227929Y-152763D01*
Y-135263D01*
G01X-215451D02*
Y-152763D01*
G01X-220473Y-135263D02*
X-210429D01*
G01X-202318Y-152763D02*
Y-135263D01*
X-196859D01*
X-195113Y-136138D01*
X-194021Y-137305D01*
X-193584Y-139638D01*
X-194021Y-141972D01*
X-195331Y-143430D01*
X-196859Y-144305D01*
X-202318D01*
G01X-196859D02*
X-193584Y-152763D01*
G01X-180451D02*
X-182198Y-152471D01*
X-183726Y-151305D01*
X-185036Y-149555D01*
X-185910Y-147513D01*
X-186346Y-145180D01*
Y-142846D01*
X-185910Y-140513D01*
X-185036Y-138471D01*
X-183726Y-136722D01*
X-182198Y-135555D01*
X-180451Y-135263D01*
X-178705Y-135555D01*
X-177176Y-136722D01*
X-175866Y-138471D01*
X-174992Y-140513D01*
X-174556Y-142846D01*
Y-145180D01*
X-174992Y-147513D01*
X-175866Y-149555D01*
X-177176Y-151305D01*
X-178705Y-152471D01*
X-180451Y-152763D01*
G01X-167318Y-135263D02*
Y-152763D01*
X-158584D01*
G01X-126205Y-143430D02*
X-125331Y-142555D01*
X-124676Y-141097D01*
X-124239Y-139054D01*
X-124676Y-137305D01*
X-125549Y-136138D01*
X-127078Y-135263D01*
X-132973D01*
Y-152763D01*
X-125768D01*
X-124239Y-151597D01*
X-123366Y-149846D01*
X-122929Y-147805D01*
X-123366Y-145763D01*
X-124676Y-144013D01*
X-126205Y-143430D01*
X-132973D01*
G01X-110451Y-152763D02*
X-112198Y-152471D01*
X-113726Y-151305D01*
X-115036Y-149555D01*
X-115910Y-147513D01*
X-116346Y-145180D01*
Y-142846D01*
X-115910Y-140513D01*
X-115036Y-138471D01*
X-113726Y-136722D01*
X-112198Y-135555D01*
X-110451Y-135263D01*
X-108705Y-135555D01*
X-107176Y-136722D01*
X-105866Y-138471D01*
X-104992Y-140513D01*
X-104556Y-142846D01*
Y-145180D01*
X-104992Y-147513D01*
X-105866Y-149555D01*
X-107176Y-151305D01*
X-108705Y-152471D01*
X-110451Y-152763D01*
G01X-98410D02*
X-92951Y-135263D01*
X-87492Y-152763D01*
G01X-89458Y-146638D02*
X-96445D01*
G01X-79818Y-152763D02*
Y-135263D01*
X-74359D01*
X-72613Y-136138D01*
X-71521Y-137305D01*
X-71084Y-139638D01*
X-71521Y-141972D01*
X-72831Y-143430D01*
X-74359Y-144305D01*
X-79818D01*
G01X-74359D02*
X-71084Y-152763D01*
G01X-62754D02*
Y-135263D01*
X-58388D01*
X-56641Y-136138D01*
X-55331Y-137305D01*
X-54239Y-139054D01*
X-53366Y-141097D01*
X-53148Y-144013D01*
X-53366Y-146930D01*
X-54239Y-148972D01*
X-55331Y-150722D01*
X-56641Y-151888D01*
X-58388Y-152763D01*
X-62754D01*
G01X-282378Y-107763D02*
Y-90263D01*
X-276701Y-104846D01*
X-271024Y-90263D01*
Y-107763D01*
G01X-259201D02*
X-260511Y-107471D01*
X-261821Y-106305D01*
X-262695Y-104263D01*
X-263131Y-101930D01*
X-262695Y-99596D01*
X-261821Y-97555D01*
X-260511Y-96388D01*
X-259201Y-96097D01*
X-257891Y-96388D01*
X-256581Y-97555D01*
X-255708Y-99596D01*
X-255489Y-101930D01*
X-255708Y-104263D01*
X-256581Y-106305D01*
X-257891Y-107471D01*
X-259201Y-107763D01*
G01X-237771Y-90263D02*
Y-107763D01*
G01Y-105139D02*
X-238644Y-106597D01*
X-239955Y-107471D01*
X-241483Y-107763D01*
X-243229Y-107180D01*
X-244539Y-105722D01*
X-245413Y-103972D01*
X-245631Y-101930D01*
X-245413Y-99888D01*
X-244539Y-98138D01*
X-243229Y-96680D01*
X-241483Y-96097D01*
X-239955Y-96388D01*
X-238863Y-96972D01*
X-237771Y-98138D01*
G01X-227476Y-99888D02*
X-220489D01*
X-221144Y-97846D01*
X-222236Y-96680D01*
X-223764Y-96097D01*
X-225293Y-96388D01*
X-226603Y-97263D01*
X-227476Y-99305D01*
X-227913Y-101055D01*
Y-102805D01*
X-227476Y-104555D01*
X-226384Y-106305D01*
X-225074Y-107471D01*
X-223546Y-107763D01*
X-222018Y-107180D01*
X-220489Y-105430D01*
G01X-206701Y-107763D02*
Y-90263D01*
G01X-222441Y169326D02*
Y39370D01*
G01D02*
G03X-214567Y31496I7874J0D01*
G01X-242126Y15000D02*
G03X-227126Y0I15000J0D01*
G01X-242126Y1953504D02*
Y15000D01*
G01X-215453Y19685D02*
G03I-6988J0D01*
G01X-84646Y0D02*
X-227126D01*
G01X-215453Y19685D02*
G03I-6988J0D01*
G01D02*
G03I-6988J0D01*
G01X-214567Y169326D02*
G03X-222441I-3937J0D01*
G01X-214567D02*
G03X-222441I-3937J0D01*
G01Y436255D02*
Y200034D01*
G01D02*
G03X-214567I3937J0D01*
G01X-222441D02*
G03X-214567I3937J0D01*
G01Y436255D02*
G03X-222441I-3937J0D01*
G01X-214567D02*
G03X-222441I-3937J0D01*
G01Y703184D02*
Y466963D01*
G01D02*
G03X-214567I3937J0D01*
G01X-222441D02*
G03X-214567I3937J0D01*
G01Y703184D02*
G03X-222441I-3937J0D01*
G01X-214567D02*
G03X-222441I-3937J0D01*
G01Y970901D02*
Y733892D01*
G01D02*
G03X-214567I3937J0D01*
G01X-222441D02*
G03X-214567I3937J0D01*
G01X-222441Y1234681D02*
Y997672D01*
G01X-214567Y970901D02*
G03X-222441I-3937J0D01*
G01Y997672D02*
G03X-214567I3937J0D01*
G01Y970901D02*
G03X-222441I-3937J0D01*
G01Y997672D02*
G03X-214567I3937J0D01*
G01X-222441Y1501610D02*
Y1265389D01*
G01D02*
G03X-214567I3937J0D01*
G01Y1234681D02*
G03X-222441I-3937J0D01*
G01Y1265389D02*
G03X-214567I3937J0D01*
G01Y1234681D02*
G03X-222441I-3937J0D01*
G01X-214567Y1501610D02*
G03X-222441I-3937J0D01*
G01X-214567D02*
G03X-222441I-3937J0D01*
G01Y1768539D02*
Y1532318D01*
G01D02*
G03X-214567I3937J0D01*
G01X-222441D02*
G03X-214567I3937J0D01*
G01Y1768539D02*
G03X-222441I-3937J0D01*
G01X-214567D02*
G03X-222441I-3937J0D01*
G01Y1799247D02*
G03X-214567I3937J0D01*
G01X-222441D02*
G03X-214567I3937J0D01*
G01X-222441Y1929134D02*
Y1799247D01*
G01X-214567Y1937008D02*
G03X-222441Y1929134I0J-7874D01*
G01X-227126Y1968504D02*
G03X-242126Y1953504I0J-15000D01*
G01X-215453Y1948819D02*
G03I-6988J0D01*
G01X-84638Y1968504D02*
X-227126D01*
G01X-215453Y1948819D02*
G03I-6988J0D01*
G01D02*
G03I-6988J0D01*
G01X-214567Y43307D02*
G03X-210630Y39370I3937J0D01*
G01X-214567Y43307D02*
G03X-210630Y39370I3937J0D01*
G01X-80709D02*
X-210630D01*
G01X-80709D02*
X-210630D01*
G01X-206693Y31496D02*
X-214567D01*
G01X-175984D02*
X-84646D01*
G01X-206693D02*
G03Y39370I0J3937D01*
G01X-175984D02*
G03Y31496I0J-3937D01*
G01X-206693D02*
X-214567D01*
G01X-84646Y0D02*
X-199567D01*
G01X-175984Y31496D02*
X-84646D01*
G01X-206693D02*
G03Y39370I0J3937D01*
G01X-175984D02*
G03Y31496I0J-3937D01*
G01X-214567Y43307D02*
Y1925197D01*
G01Y43307D02*
Y1925197D01*
G01Y149606D02*
Y43307D01*
G01Y149606D02*
Y43272D01*
G01Y1807087D02*
Y161417D01*
G01Y1807087D02*
Y161417D01*
G01Y1818898D02*
Y1925231D01*
G01Y1818898D02*
Y1925231D01*
G01X-210630Y1929134D02*
G03X-214567Y1925197I0J-3937D01*
G01X-210630Y1929134D02*
G03X-214567Y1925197I0J-3937D01*
G01X-210630Y1929134D02*
X-80709D01*
G01X-210630D02*
X-80709D01*
G01X-175984Y1937008D02*
G03Y1929134I0J-3937D01*
G01X-206693D02*
G03Y1937008I0J3937D01*
G01X-175984D02*
G03Y1929134I0J-3937D01*
G01X-206693D02*
G03Y1937008I0J3937D01*
G01X-175984D02*
X-84638D01*
G01X-214567D02*
X-206693D01*
G01X-84638Y1968504D02*
X-199567D01*
G01X-175984Y1937008D02*
X-84638D01*
G01X-214567D02*
X-206693D01*
G01X-76772Y3937D02*
G03X-72835Y0I3937J0D01*
G01X-76772Y35433D02*
G03X-80709Y39370I-3937J0D01*
G01X-76772Y35433D02*
G03X-80709Y39370I-3937J0D01*
G01X-76772Y3937D02*
G03X-72835Y0I3937J0D01*
G01X-11811D02*
X-72835D01*
G01X-11811D02*
X-72835D01*
G01X-76772Y3937D02*
Y35433D01*
G01Y3937D02*
Y35433D01*
G01X-72835Y0D02*
X-11811D01*
G01X-76772Y3937D02*
G03X-72835Y0I3937J0D01*
G01X-84646Y7874D02*
Y0D01*
G01X-76772Y7874D02*
G03X-84646I-3937J0D01*
G01Y31496D02*
G03X-76772I3937J0D01*
G01X-72835Y0D02*
X-11811D01*
G01X-76772Y3937D02*
G03X-72835Y0I3937J0D01*
G01X-84646Y7874D02*
Y0D01*
G01X-76772Y7874D02*
G03X-84646I-3937J0D01*
G01Y31496D02*
G03X-76772I3937J0D01*
G01X-80709Y1929134D02*
G03X-76772Y1933071I0J3937D01*
G01X-80709Y1929134D02*
G03X-76772Y1933071I0J3937D01*
G01D02*
Y1964567D01*
G01Y1933071D02*
Y1964567D01*
G01X-76763Y1937008D02*
G03X-84638I-3937J0D01*
G01X-72835Y1968504D02*
G03X-76772Y1964567I0J-3937D01*
G01X-72835Y1968504D02*
G03X-76772Y1964567I0J-3937D01*
G01X-72835Y1968504D02*
X-11811D01*
G01X-72835D02*
X-11811D01*
G01X-72835D02*
G03X-76772Y1964567I0J-3937D01*
G01X-11811Y1968504D02*
X-72835D01*
G01X-84638Y1960889D02*
Y1968504D01*
G01Y1960889D02*
G03X-76763I3938J0D01*
G01X-72835Y1968504D02*
G03X-76772Y1964567I0J-3937D01*
G01X-11811Y1968504D02*
X-72835D01*
G01X-84638Y1960889D02*
Y1968504D01*
G01Y1960889D02*
G03X-76763I3938J0D01*
G01X-14018Y-107763D02*
Y-90263D01*
X-8778D01*
X-7031Y-91138D01*
X-5721Y-93180D01*
X-5284Y-95513D01*
X-5721Y-97846D01*
X-6813Y-99596D01*
X-8778Y-100472D01*
X-14018D01*
G01X12652Y-91722D02*
X11342Y-90846D01*
X9814Y-90263D01*
X8067D01*
X6102Y-91138D01*
X4574Y-92596D01*
X3482Y-94347D01*
X2609Y-97263D01*
X2390Y-99888D01*
X2827Y-102513D01*
X3482Y-104263D01*
X4792Y-106013D01*
X6321Y-107180D01*
X7849Y-107763D01*
X9377D01*
X10906Y-107180D01*
X12216Y-106305D01*
X13308Y-105139D01*
G01X27095Y-98430D02*
X27969Y-97555D01*
X28624Y-96097D01*
X29061Y-94054D01*
X28624Y-92305D01*
X27751Y-91138D01*
X26222Y-90263D01*
X20327D01*
Y-107763D01*
X27532D01*
X29061Y-106597D01*
X29934Y-104846D01*
X30371Y-102805D01*
X29934Y-100763D01*
X28624Y-99013D01*
X27095Y-98430D01*
X20327D01*
G01X36299Y-113596D02*
X49399D01*
G01X55327Y-107763D02*
Y-90263D01*
X65371Y-107763D01*
Y-90263D01*
G01X77849Y-107763D02*
X76102Y-107471D01*
X74574Y-106305D01*
X73264Y-104555D01*
X72390Y-102513D01*
X71954Y-100180D01*
Y-97846D01*
X72390Y-95513D01*
X73264Y-93471D01*
X74574Y-91722D01*
X76102Y-90555D01*
X77849Y-90263D01*
X79595Y-90555D01*
X81124Y-91722D01*
X82434Y-93471D01*
X83308Y-95513D01*
X83744Y-97846D01*
Y-100180D01*
X83308Y-102513D01*
X82434Y-104555D01*
X81124Y-106305D01*
X79595Y-107471D01*
X77849Y-107763D01*
G01X-901Y-152763D02*
Y-135263D01*
X-3521Y-138763D01*
G01Y-152763D02*
X1719D01*
G01X12451Y-138180D02*
X13761Y-136430D01*
X15289Y-135555D01*
X17036Y-135263D01*
X19219Y-135846D01*
X20747Y-137305D01*
X21184Y-139054D01*
X20966Y-140805D01*
X20092Y-142263D01*
X15726Y-145180D01*
X13761Y-147221D01*
X12451Y-150139D01*
X12014Y-152763D01*
X21184D01*
G01X36719D02*
Y-135263D01*
X28640Y-147805D01*
X39558D01*
G01X46796Y-149263D02*
X48105Y-151305D01*
X49852Y-152471D01*
X51817Y-152763D01*
X53564Y-152471D01*
X55311Y-151013D01*
X56402Y-149263D01*
X56621Y-147513D01*
X56184Y-145472D01*
X54656Y-144013D01*
X53127Y-143430D01*
X51162D01*
G01X53127D02*
X54437Y-142555D01*
X55529Y-141097D01*
X55966Y-139347D01*
X55529Y-137596D01*
X54437Y-136138D01*
X52472Y-135263D01*
X50507Y-135555D01*
X48542Y-136722D01*
G01X64296Y-149263D02*
X65605Y-151305D01*
X67352Y-152471D01*
X69317Y-152763D01*
X71064Y-152471D01*
X72811Y-151013D01*
X73902Y-149263D01*
X74121Y-147513D01*
X73684Y-145472D01*
X72156Y-144013D01*
X70627Y-143430D01*
X68662D01*
G01X70627D02*
X71937Y-142555D01*
X73029Y-141097D01*
X73466Y-139347D01*
X73029Y-137596D01*
X71937Y-136138D01*
X69972Y-135263D01*
X68007Y-135555D01*
X66042Y-136722D01*
G01X-11811Y0D02*
G03X-7874Y3937I0J3937D01*
G01X-11811Y0D02*
G03X-7874Y3937I0J3937D01*
G01Y43110D02*
Y3937D01*
G01Y43110D02*
Y3937D01*
G01X0D02*
G03X3937Y0I3937J0D01*
G01X0Y3937D02*
G03X3937Y0I3937J0D01*
G01X0Y3937D02*
Y43110D01*
G01Y3937D02*
Y43110D01*
G01X64961Y0D02*
X3937D01*
G01X64961D02*
X3937D01*
G01X0Y3937D02*
G03X3937Y0I3937J0D01*
G01X0Y1964567D02*
Y3937D01*
G01X3937Y0D02*
X64961D01*
G01X-7874Y3937D02*
Y1964567D01*
G01X-11811Y0D02*
G03X-7874Y3937I0J3937D01*
G01X0Y11811D02*
G03X-7874I-3937J0D01*
G01Y42520D02*
G03X0I3937J0D01*
G01Y3937D02*
G03X3937Y0I3937J0D01*
G01X0Y1964567D02*
Y3937D01*
G01X3937Y0D02*
X64961D01*
G01X-7874Y3937D02*
Y1964567D01*
G01X-11811Y0D02*
G03X-7874Y3937I0J3937D01*
G01X0Y11811D02*
G03X-7874I-3937J0D01*
G01Y42520D02*
G03X0I3937J0D01*
G01X-7874Y93110D02*
Y43110D01*
G01Y93110D02*
Y43110D01*
G01X0D02*
Y93110D01*
G01Y43110D02*
Y93110D01*
G01X-7874Y214764D02*
Y93110D01*
G01Y214764D02*
Y93110D01*
G01X0D02*
Y214764D01*
G01Y93110D02*
Y214764D01*
G01X-7874Y226968D02*
Y214764D01*
G01Y226968D02*
Y214764D01*
G01Y342461D02*
Y226968D01*
G01Y342461D02*
Y226968D01*
G01X0Y226969D02*
Y342461D01*
G01Y226969D02*
Y342461D01*
G01Y214764D02*
Y226969D01*
G01Y214764D02*
Y226969D01*
G01Y278740D02*
G03X-7874I-3937J0D01*
G01X0D02*
G03X-7874I-3937J0D01*
G01Y354665D02*
Y342461D01*
G01Y354665D02*
Y342461D01*
G01X0D02*
Y354665D01*
G01Y342461D02*
Y354665D01*
G01X-7874Y309449D02*
G03X0I3937J0D01*
G01X-7874D02*
G03X0I3937J0D01*
G01X-7874Y476339D02*
Y354665D01*
G01Y476339D02*
Y354665D01*
G01X0D02*
Y476339D01*
G01Y354665D02*
Y476339D01*
G01X-7874Y526339D02*
Y476339D01*
G01Y526339D02*
Y476339D01*
G01X0D02*
Y526339D01*
G01Y476339D02*
Y526339D01*
G01X-7874Y736181D02*
Y526339D01*
G01Y736181D02*
Y526339D01*
G01X0D02*
Y736181D01*
G01Y526339D02*
Y736181D01*
G01Y545669D02*
G03X-7874I-3937J0D01*
G01X0D02*
G03X-7874I-3937J0D01*
G01Y576378D02*
G03X0I3937J0D01*
G01X-7874D02*
G03X0I3937J0D01*
G01X-7874Y786181D02*
Y736181D01*
G01Y786181D02*
Y736181D01*
G01X0D02*
Y786181D01*
G01Y736181D02*
Y786181D01*
G01X-7874Y907815D02*
Y786181D01*
G01Y907815D02*
Y786181D01*
G01X0D02*
Y907815D01*
G01Y786181D02*
Y907815D01*
G01X-7874Y862205D02*
G03X0I3937J0D01*
G01Y831496D02*
G03X-7874I-3937J0D01*
G01Y862205D02*
G03X0I3937J0D01*
G01Y831496D02*
G03X-7874I-3937J0D01*
G01Y920020D02*
Y907815D01*
G01Y920020D02*
Y907815D01*
G01X0D02*
Y920020D01*
G01Y907815D02*
Y920020D01*
G01X-7874Y1048484D02*
Y920020D01*
G01Y1048484D02*
Y920020D01*
G01X0D02*
Y1048484D01*
G01Y920020D02*
Y1048484D01*
G01X-7874Y1060689D02*
Y1048484D01*
G01Y1060689D02*
Y1048484D01*
G01Y1182323D02*
Y1060689D01*
G01Y1182323D02*
Y1060689D01*
G01X0D02*
Y1182323D01*
G01Y1060689D02*
Y1182323D01*
G01Y1048484D02*
Y1060689D01*
G01Y1048484D02*
Y1060689D01*
G01Y1106299D02*
G03X-7874I-3937J0D01*
G01X0D02*
G03X-7874I-3937J0D01*
G01Y1137008D02*
G03X0I3937J0D01*
G01X-7874D02*
G03X0I3937J0D01*
G01X-7874Y1232323D02*
Y1182323D01*
G01Y1232323D02*
Y1182323D01*
G01X0D02*
Y1232323D01*
G01Y1182323D02*
Y1232323D01*
G01X-7874Y1442165D02*
Y1232323D01*
G01Y1442165D02*
Y1232323D01*
G01X0D02*
Y1442165D01*
G01Y1232323D02*
Y1442165D01*
G01X-7874Y1422835D02*
G03X0I3937J0D01*
G01Y1392126D02*
G03X-7874I-3937J0D01*
G01Y1422835D02*
G03X0I3937J0D01*
G01Y1392126D02*
G03X-7874I-3937J0D01*
G01Y1492165D02*
Y1442165D01*
G01Y1492165D02*
Y1442165D01*
G01X0D02*
Y1492165D01*
G01Y1442165D02*
Y1492165D01*
G01X-7874Y1613839D02*
Y1492165D01*
G01Y1613839D02*
Y1492165D01*
G01X0D02*
Y1613839D01*
G01Y1492165D02*
Y1613839D01*
G01X-7874Y1626043D02*
Y1613839D01*
G01Y1626043D02*
Y1613839D01*
G01Y1741535D02*
Y1626043D01*
G01Y1741535D02*
Y1626043D01*
G01X0D02*
Y1741535D01*
G01Y1626043D02*
Y1741535D01*
G01Y1613839D02*
Y1626043D01*
G01Y1613839D02*
Y1626043D01*
G01Y1659055D02*
G03X-7874I-3937J0D01*
G01X0D02*
G03X-7874I-3937J0D01*
G01Y1689764D02*
G03X0I3937J0D01*
G01X-7874D02*
G03X0I3937J0D01*
G01X-7874Y1753740D02*
Y1741535D01*
G01Y1753740D02*
Y1741535D01*
G01Y1875394D02*
Y1753740D01*
G01Y1875394D02*
Y1753740D01*
G01X0D02*
Y1875394D01*
G01Y1753740D02*
Y1875394D01*
G01Y1741535D02*
Y1753740D01*
G01Y1741535D02*
Y1753740D01*
G01X-7874Y1925394D02*
Y1875394D01*
G01Y1925394D02*
Y1875394D01*
G01X0D02*
Y1925394D01*
G01Y1875394D02*
Y1925394D01*
G01X-7874Y1964567D02*
Y1925394D01*
G01Y1964567D02*
Y1925394D01*
G01X0D02*
Y1964567D01*
G01Y1925394D02*
Y1964567D01*
G01Y1925984D02*
G03X-7874I-3937J0D01*
G01X0D02*
G03X-7874I-3937J0D01*
G01Y1964567D02*
G03X-11811Y1968504I-3937J0D01*
G01X-7874Y1964567D02*
G03X-11811Y1968504I-3937J0D01*
G01X3937D02*
G03X0Y1964567I0J-3937D01*
G01X3937Y1968504D02*
G03X0Y1964567I0J-3937D01*
G01X3937Y1968504D02*
X64961D01*
G01X3937D02*
X64961D01*
G01X3937D02*
G03X0Y1964567I0J-3937D01*
G01X64961Y1968504D02*
X3937D01*
G01X-7874Y1964567D02*
G03X-11811Y1968504I-3937J0D01*
G01X-7874Y1956693D02*
G03X0I3937J0D01*
G01X3937Y1968504D02*
G03X0Y1964567I0J-3937D01*
G01X64961Y1968504D02*
X3937D01*
G01X-7874Y1964567D02*
G03X-11811Y1968504I-3937J0D01*
G01X-7874Y1956693D02*
G03X0I3937J0D01*
G01X168110Y31496D02*
X76763D01*
G01X72835Y39370D02*
G03X68898Y35433I0J-3937D01*
G01X72835Y39370D02*
G03X68898Y35433I0J-3937D01*
G01X64961Y0D02*
G03X68898Y3937I0J3937D01*
G01X64961Y0D02*
G03X68898Y3937I0J3937D01*
G01Y35433D02*
Y3937D01*
G01Y35433D02*
Y3937D01*
G01X202756Y39370D02*
X72835D01*
G01X202756D02*
X72835D01*
G01D02*
X202756D01*
G01X72835D02*
G03X68898Y35433I0J-3937D01*
G01Y3937D02*
Y35485D01*
G01X64961Y0D02*
G03X68898Y3937I0J3937D01*
G01X76763D02*
G03X80700Y0I3937J0D01*
G01X76763Y7615D02*
Y3937D01*
G01X80700Y0D02*
X340551D01*
G01X168110Y31496D02*
X76763D01*
G01Y7615D02*
G03X68889I-3937J0D01*
G01Y31496D02*
G03X76763I3937J0D01*
G01X72835Y39370D02*
X202756D01*
G01X72835D02*
G03X68898Y35433I0J-3937D01*
G01Y3937D02*
Y35485D01*
G01X64961Y0D02*
G03X68898Y3937I0J3937D01*
G01X76763D02*
G03X80700Y0I3937J0D01*
G01X76763Y7615D02*
Y3937D01*
G01X80700Y0D02*
X340551D01*
G01X168110Y31496D02*
X76763D01*
G01Y7615D02*
G03X68889I-3937J0D01*
G01Y31496D02*
G03X76763I3937J0D01*
G01X68898Y1933071D02*
G03X72835Y1929134I3937J0D01*
G01X68898Y1933071D02*
G03X72835Y1929134I3937J0D01*
G01D02*
X202756D01*
G01X72835D02*
X202756D01*
G01X68898Y1964567D02*
Y1933071D01*
G01Y1964567D02*
Y1933071D01*
G01D02*
Y1964567D01*
G01Y1933071D02*
G03X72835Y1929134I3937J0D01*
G01X202756D02*
X72835D01*
G01X68898Y1933071D02*
Y1964567D01*
G01Y1933071D02*
G03X72835Y1929134I3937J0D01*
G01X202756D02*
X72835D01*
G01X68898Y1964567D02*
G03X64961Y1968504I-3937J0D01*
G01X68898Y1964567D02*
G03X64961Y1968504I-3937J0D01*
G01X68898Y1964567D02*
G03X64961Y1968504I-3937J0D01*
G01X109377D02*
X80709D01*
G01D02*
G03X76772Y1964567I0J-3937D01*
G01Y1960630D02*
Y1964567D01*
G01X168110Y1937008D02*
X76772D01*
G01X68898Y1960630D02*
G03X76772I3937J0D01*
G01Y1937008D02*
G03X68898I-3937J0D01*
G01Y1964567D02*
G03X64961Y1968504I-3937J0D01*
G01X109377D02*
X80709D01*
G01D02*
G03X76772Y1964567I0J-3937D01*
G01Y1960630D02*
Y1964567D01*
G01X168110Y1937008D02*
X76772D01*
G01X68898Y1960630D02*
G03X76772I3937J0D01*
G01Y1937008D02*
G03X68898I-3937J0D01*
G01X128690Y-90263D02*
X134149Y-107763D01*
X139608Y-90263D01*
G01X156016Y-107763D02*
X147282D01*
Y-90263D01*
X156016D01*
G01X152522Y-98721D02*
X147282D01*
G01X164782Y-107763D02*
Y-90263D01*
X170241D01*
X171987Y-91138D01*
X173079Y-92305D01*
X173516Y-94638D01*
X173079Y-96972D01*
X171769Y-98430D01*
X170241Y-99305D01*
X164782D01*
G01X170241D02*
X173516Y-107763D01*
G01X186649Y-108346D02*
X186212Y-108055D01*
Y-107471D01*
X186649Y-107180D01*
X187086Y-107471D01*
Y-108055D01*
X186649Y-108346D01*
G01X118011Y1968504D02*
X142520D01*
G01X109377D02*
X110137D01*
G01D02*
G03X118011I3937J0D01*
G01X110137D02*
G03X118011I3937J0D01*
G01X147501Y-138180D02*
X148811Y-136430D01*
X150339Y-135555D01*
X152086Y-135263D01*
X154269Y-135846D01*
X155797Y-137305D01*
X156234Y-139054D01*
X156016Y-140805D01*
X155142Y-142263D01*
X150776Y-145180D01*
X148811Y-147221D01*
X147501Y-150139D01*
X147064Y-152763D01*
X156234D01*
G01X163690D02*
X169149Y-135263D01*
X174608Y-152763D01*
G01X172642Y-146638D02*
X165655D01*
G01X168110Y31496D02*
G03Y39370I0J3937D01*
G01Y31496D02*
G03Y39370I0J3937D01*
G01Y1929134D02*
G03Y1937008I0J3937D01*
G01Y1929134D02*
G03Y1937008I0J3937D01*
G01X340559Y1968504D02*
X142520D01*
G01X340559D02*
X142520D01*
G01X202756Y39370D02*
G03X206693Y43307I0J3937D01*
G01X202756Y39370D02*
G03X206693Y43307I0J3937D01*
G01X202756Y39370D02*
G03X206693Y43307I0J3937D01*
G01X218504Y39370D02*
X348425D01*
G01X214567Y43307D02*
G03X218504Y39370I3937J0D01*
G01X222441Y31496D02*
X198819D01*
G01X222441D02*
G03Y39370I0J3937D01*
G01X198819D02*
G03Y31496I0J-3937D01*
G01X202756Y39370D02*
G03X206693Y43307I0J3937D01*
G01X218504Y39370D02*
X348425D01*
G01X214567Y43307D02*
G03X218504Y39370I3937J0D01*
G01X222441Y31496D02*
X198819D01*
G01X222441D02*
G03Y39370I0J3937D01*
G01X198819D02*
G03Y31496I0J-3937D01*
G01X214567Y161417D02*
Y43307D01*
G01X206693Y1925197D02*
Y43307D01*
G01Y1925197D02*
Y43307D01*
G01Y161417D02*
Y1807087D01*
G01X214567D02*
Y161417D01*
G01Y169291D02*
G03X206693I-3937J0D01*
G01Y161417D02*
Y1807087D01*
G01X214567D02*
Y161417D01*
G01Y169291D02*
G03X206693I-3937J0D01*
G01Y200000D02*
G03X214567I3937J0D01*
G01X206693D02*
G03X214567I3937J0D01*
G01Y436220D02*
G03X206693I-3937J0D01*
G01X214567D02*
G03X206693I-3937J0D01*
G01Y466929D02*
G03X214567I3937J0D01*
G01X206693D02*
G03X214567I3937J0D01*
G01Y703149D02*
G03X206693I-3937J0D01*
G01X214567D02*
G03X206693I-3937J0D01*
G01Y733858D02*
G03X214567I3937J0D01*
G01X206693D02*
G03X214567I3937J0D01*
G01Y970867D02*
G03X206693I-3937J0D01*
G01Y997637D02*
G03X214567I3937J0D01*
G01Y970867D02*
G03X206693I-3937J0D01*
G01Y997637D02*
G03X214567I3937J0D01*
G01X206693Y1265355D02*
G03X214567I3937J0D01*
G01Y1234646D02*
G03X206693I-3937J0D01*
G01Y1265355D02*
G03X214567I3937J0D01*
G01Y1234646D02*
G03X206693I-3937J0D01*
G01X214567Y1501575D02*
G03X206693I-3937J0D01*
G01X214567D02*
G03X206693I-3937J0D01*
G01Y1532284D02*
G03X214567I3937J0D01*
G01X206693D02*
G03X214567I3937J0D01*
G01Y1768504D02*
G03X206693I-3937J0D01*
G01X214567D02*
G03X206693I-3937J0D01*
G01X214567Y1807087D02*
Y1925197D01*
G01X206693Y1799213D02*
G03X214567I3937J0D01*
G01X206693D02*
G03X214567I3937J0D01*
G01X206693Y1925197D02*
G03X202756Y1929134I-3937J0D01*
G01X206693Y1925197D02*
G03X202756Y1929134I-3937J0D01*
G01X206693Y1925197D02*
G03X202756Y1929134I-3937J0D01*
G01X218504D02*
G03X214567Y1925197I0J-3937D01*
G01X348425Y1929134D02*
X218504D01*
G01X198819Y1937008D02*
G03Y1929134I0J-3937D01*
G01X222441D02*
G03Y1937008I0J3937D01*
G01X206693Y1925197D02*
G03X202756Y1929134I-3937J0D01*
G01X218504D02*
G03X214567Y1925197I0J-3937D01*
G01X348425Y1929134D02*
X218504D01*
G01X198819Y1937008D02*
G03Y1929134I0J-3937D01*
G01X222441D02*
G03Y1937008I0J3937D01*
G01X198819D02*
X222441D01*
G01X198819D02*
X222441D01*
G01X253482Y-90263D02*
Y-107763D01*
X262216D01*
G01X279279D02*
Y-96097D01*
G01Y-98138D02*
X278406Y-96972D01*
X277095Y-96388D01*
X275567Y-96097D01*
X274039Y-96680D01*
X272729Y-97846D01*
X271855Y-99596D01*
X271419Y-101930D01*
X271855Y-104263D01*
X272729Y-106013D01*
X274039Y-107180D01*
X275567Y-107763D01*
X277095Y-107471D01*
X278406Y-106597D01*
X279279Y-105430D01*
G01X288264Y-113013D02*
X289574Y-113596D01*
X291321Y-113013D01*
X292412Y-111847D01*
X293286Y-110388D01*
X294595Y-105722D01*
X297434Y-96097D01*
G01X290447D02*
X294595Y-105722D01*
G01X307074Y-99888D02*
X314061D01*
X313406Y-97846D01*
X312314Y-96680D01*
X310786Y-96097D01*
X309257Y-96388D01*
X307947Y-97263D01*
X307074Y-99305D01*
X306637Y-101055D01*
Y-102805D01*
X307074Y-104555D01*
X308166Y-106305D01*
X309476Y-107471D01*
X311004Y-107763D01*
X312532Y-107180D01*
X314061Y-105430D01*
G01X324792Y-107763D02*
Y-96097D01*
G01Y-98430D02*
X325884Y-97263D01*
X326976Y-96388D01*
X328504Y-96097D01*
X329595Y-96388D01*
X330906Y-97263D01*
G01X342074Y-105722D02*
X343166Y-106888D01*
X344694Y-107763D01*
X346004D01*
X347314Y-107180D01*
X348187Y-106305D01*
X348624Y-105139D01*
X348406Y-103388D01*
X347532Y-102513D01*
X343602Y-100763D01*
X342729Y-98721D01*
X343166Y-97263D01*
X344039Y-96388D01*
X345349Y-96097D01*
X346659Y-96388D01*
X347969Y-97263D01*
G01X242549Y-135263D02*
X245605Y-152763D01*
X249099Y-135263D01*
X252592Y-152763D01*
X255649Y-135263D01*
G01X262014Y-150430D02*
X263761Y-151888D01*
X265726Y-152763D01*
X267472D01*
X269219Y-151888D01*
X270529Y-150430D01*
X271184Y-148388D01*
X270747Y-146347D01*
X269656Y-144596D01*
X267691Y-143430D01*
X265071Y-142846D01*
X263542Y-141680D01*
X262887Y-139638D01*
X263324Y-137596D01*
X264416Y-136138D01*
X265944Y-135263D01*
X267472D01*
X269001Y-135846D01*
X270311Y-137305D01*
G01X281479Y-135263D02*
X286719D01*
G01X284099D02*
Y-152763D01*
G01X281479D02*
X286719D01*
G01X297232Y-135263D02*
Y-152763D01*
X305966D01*
G01X314296D02*
Y-135263D01*
G01X322592D02*
X314296Y-146055D01*
G01X323902Y-152763D02*
X318007Y-141097D01*
G01X330049Y-158596D02*
X343149D01*
G01X354099Y-135263D02*
Y-152763D01*
G01X349077Y-135263D02*
X359121D01*
G01X253150Y31496D02*
X344488D01*
G01X253150Y39370D02*
G03Y31496I0J-3937D01*
G01D02*
X344488D01*
G01X253150Y39370D02*
G03Y31496I0J-3937D01*
G01Y1937008D02*
G03Y1929134I0J-3937D01*
G01Y1937008D02*
G03Y1929134I0J-3937D01*
G01Y1937008D02*
X344496D01*
G01X253150D02*
X344496D01*
G01X340551Y0D02*
G03X344488Y3937I0J3937D01*
G01X340551Y0D02*
G03X344488Y3937I0J3937D01*
G01X344496Y1964567D02*
G03X340559Y1968504I-3937J0D01*
G01X344496Y1964567D02*
G03X340559Y1968504I-3937J0D01*
G01X356299Y0D02*
X417323D01*
G01X352362Y3937D02*
G03X356299Y0I3937J0D01*
G01X352362Y35433D02*
Y3937D01*
G01Y35433D02*
G03X348425Y39370I-3937J0D01*
G01X344488Y7874D02*
Y3937D01*
G01X352362Y7874D02*
G03X344488I-3937J0D01*
G01Y31496D02*
G03X352362I3937J0D01*
G01X356299Y0D02*
X417323D01*
G01X352362Y3937D02*
G03X356299Y0I3937J0D01*
G01X352362Y35433D02*
Y3937D01*
G01Y35433D02*
G03X348425Y39370I-3937J0D01*
G01X344488Y7874D02*
Y3937D01*
G01X352362Y7874D02*
G03X344488I-3937J0D01*
G01Y31496D02*
G03X352362I3937J0D01*
G01X348425Y1929134D02*
G03X352362Y1933071I0J3937D01*
G01Y1964567D02*
Y1933071D01*
G01X348425Y1929134D02*
G03X352362Y1933071I0J3937D01*
G01Y1964567D02*
Y1933071D01*
G01X356299Y1968504D02*
G03X352362Y1964567I0J-3937D01*
G01X417323Y1968504D02*
X356299D01*
G01X344496Y1960889D02*
Y1964567D01*
G01Y1960889D02*
G03X352370I3937J0D01*
G01Y1937008D02*
G03X344496I-3937J0D01*
G01X356299Y1968504D02*
G03X352362Y1964567I0J-3937D01*
G01X417323Y1968504D02*
X356299D01*
G01X344496Y1960889D02*
Y1964567D01*
G01Y1960889D02*
G03X352370I3937J0D01*
G01Y1937008D02*
G03X344496I-3937J0D01*
G01X404346Y-107763D02*
Y-90263D01*
X408712D01*
X410459Y-91138D01*
X411769Y-92305D01*
X412861Y-94054D01*
X413734Y-96097D01*
X413952Y-99013D01*
X413734Y-101930D01*
X412861Y-103972D01*
X411769Y-105722D01*
X410459Y-106888D01*
X408712Y-107763D01*
X404346D01*
G01X423374Y-99888D02*
X430361D01*
X429706Y-97846D01*
X428614Y-96680D01*
X427086Y-96097D01*
X425557Y-96388D01*
X424247Y-97263D01*
X423374Y-99305D01*
X422937Y-101055D01*
Y-102805D01*
X423374Y-104555D01*
X424466Y-106305D01*
X425776Y-107471D01*
X427304Y-107763D01*
X428832Y-107180D01*
X430361Y-105430D01*
G01X440874Y-105722D02*
X441966Y-106888D01*
X443494Y-107763D01*
X444804D01*
X446114Y-107180D01*
X446987Y-106305D01*
X447424Y-105139D01*
X447206Y-103388D01*
X446332Y-102513D01*
X442402Y-100763D01*
X441529Y-98721D01*
X441966Y-97263D01*
X442839Y-96388D01*
X444149Y-96097D01*
X445459Y-96388D01*
X446769Y-97263D01*
G01X461649Y-96097D02*
Y-107763D01*
G01Y-91430D02*
X461212Y-91138D01*
Y-90555D01*
X461649Y-90263D01*
X462086Y-90555D01*
Y-91138D01*
X461649Y-91430D01*
G01X476092Y-112138D02*
X477621Y-113305D01*
X479367Y-113596D01*
X480895Y-113305D01*
X482206Y-111847D01*
X483079Y-109805D01*
Y-96097D01*
G01Y-98430D02*
X482206Y-97263D01*
X480895Y-96388D01*
X479367Y-96097D01*
X477621Y-96680D01*
X476529Y-97846D01*
X475655Y-99888D01*
X475219Y-101930D01*
X475437Y-103680D01*
X476311Y-105722D01*
X477621Y-107180D01*
X479367Y-107763D01*
X480677Y-107471D01*
X482206Y-106305D01*
X483079Y-105139D01*
G01X492937Y-107763D02*
Y-96097D01*
G01Y-99013D02*
X493811Y-97555D01*
X495121Y-96388D01*
X496867Y-96097D01*
X498395Y-96388D01*
X499706Y-97555D01*
X500361Y-99596D01*
Y-107763D01*
G01X510874Y-99888D02*
X517861D01*
X517206Y-97846D01*
X516114Y-96680D01*
X514586Y-96097D01*
X513057Y-96388D01*
X511747Y-97263D01*
X510874Y-99305D01*
X510437Y-101055D01*
Y-102805D01*
X510874Y-104555D01*
X511966Y-106305D01*
X513276Y-107471D01*
X514804Y-107763D01*
X516332Y-107180D01*
X517861Y-105430D01*
G01X528592Y-107763D02*
Y-96097D01*
G01Y-98430D02*
X529684Y-97263D01*
X530776Y-96388D01*
X532304Y-96097D01*
X533395Y-96388D01*
X534706Y-97263D01*
G01X429722Y-152763D02*
Y-135263D01*
X435399Y-149846D01*
X441076Y-135263D01*
Y-152763D01*
G01X452899D02*
X451152Y-152471D01*
X449624Y-151305D01*
X448314Y-149555D01*
X447440Y-147513D01*
X447004Y-145180D01*
Y-142846D01*
X447440Y-140513D01*
X448314Y-138471D01*
X449624Y-136722D01*
X451152Y-135555D01*
X452899Y-135263D01*
X454645Y-135555D01*
X456174Y-136722D01*
X457484Y-138471D01*
X458358Y-140513D01*
X458794Y-142846D01*
Y-145180D01*
X458358Y-147513D01*
X457484Y-149555D01*
X456174Y-151305D01*
X454645Y-152471D01*
X452899Y-152763D01*
G01X465814Y-150430D02*
X467561Y-151888D01*
X469526Y-152763D01*
X471272D01*
X473019Y-151888D01*
X474329Y-150430D01*
X474984Y-148388D01*
X474547Y-146347D01*
X473456Y-144596D01*
X471491Y-143430D01*
X468871Y-142846D01*
X467342Y-141680D01*
X466687Y-139638D01*
X467124Y-137596D01*
X468216Y-136138D01*
X469744Y-135263D01*
X471272D01*
X472801Y-135846D01*
X474111Y-137305D01*
G01X483314Y-150430D02*
X485061Y-151888D01*
X487026Y-152763D01*
X488772D01*
X490519Y-151888D01*
X491829Y-150430D01*
X492484Y-148388D01*
X492047Y-146347D01*
X490956Y-144596D01*
X488991Y-143430D01*
X486371Y-142846D01*
X484842Y-141680D01*
X484187Y-139638D01*
X484624Y-137596D01*
X485716Y-136138D01*
X487244Y-135263D01*
X488772D01*
X490301Y-135846D01*
X491611Y-137305D01*
G01X509766Y-152763D02*
X501032D01*
Y-135263D01*
X509766D01*
G01X506272Y-143721D02*
X501032D01*
G01X429134Y3937D02*
G03X433071Y0I3937J0D01*
G01X429134Y1964567D02*
Y3937D01*
G01X433071Y0D02*
X494095D01*
G01X421260Y3937D02*
Y1964567D01*
G01X417323Y0D02*
G03X421260Y3937I0J3937D01*
G01X429134Y11811D02*
G03X421260I-3937J0D01*
G01Y42520D02*
G03X429134I3937J0D01*
G01Y3937D02*
G03X433071Y0I3937J0D01*
G01X429134Y1964567D02*
Y3937D01*
G01X433071Y0D02*
X494095D01*
G01X421260Y3937D02*
Y1964567D01*
G01X417323Y0D02*
G03X421260Y3937I0J3937D01*
G01X429134Y11811D02*
G03X421260I-3937J0D01*
G01Y42520D02*
G03X429134I3937J0D01*
G01Y278740D02*
G03X421260I-3937J0D01*
G01X429134D02*
G03X421260I-3937J0D01*
G01Y309449D02*
G03X429134I3937J0D01*
G01X421260D02*
G03X429134I3937J0D01*
G01Y545669D02*
G03X421260I-3937J0D01*
G01X429134D02*
G03X421260I-3937J0D01*
G01Y576378D02*
G03X429134I3937J0D01*
G01X421260D02*
G03X429134I3937J0D01*
G01X421260Y862205D02*
G03X429134I3937J0D01*
G01Y831496D02*
G03X421260I-3937J0D01*
G01Y862205D02*
G03X429134I3937J0D01*
G01Y831496D02*
G03X421260I-3937J0D01*
G01X429134Y1106299D02*
G03X421260I-3937J0D01*
G01X429134D02*
G03X421260I-3937J0D01*
G01Y1137008D02*
G03X429134I3937J0D01*
G01X421260D02*
G03X429134I3937J0D01*
G01X421260Y1422835D02*
G03X429134I3937J0D01*
G01Y1392126D02*
G03X421260I-3937J0D01*
G01Y1422835D02*
G03X429134I3937J0D01*
G01Y1392126D02*
G03X421260I-3937J0D01*
G01X429134Y1659055D02*
G03X421260I-3937J0D01*
G01X429134D02*
G03X421260I-3937J0D01*
G01Y1689764D02*
G03X429134I3937J0D01*
G01X421260D02*
G03X429134I3937J0D01*
G01Y1925984D02*
G03X421260I-3937J0D01*
G01X429134D02*
G03X421260I-3937J0D01*
G01X433071Y1968504D02*
G03X429134Y1964567I0J-3937D01*
G01X494095Y1968504D02*
X433071D01*
G01X421260Y1964567D02*
G03X417323Y1968504I-3937J0D01*
G01X421260Y1956693D02*
G03X429134I3937J0D01*
G01X433071Y1968504D02*
G03X429134Y1964567I0J-3937D01*
G01X494095Y1968504D02*
X433071D01*
G01X421260Y1964567D02*
G03X417323Y1968504I-3937J0D01*
G01X421260Y1956693D02*
G03X429134I3937J0D01*
G01X433071Y1968504D02*
G03X429134Y1964567I0J-3937D01*
G01X421260D02*
G03X417323Y1968504I-3937J0D01*
G01X494095Y0D02*
G03X498032Y3937I0J3937D01*
G01X494095Y0D02*
G03X498032Y3937I0J3937D01*
G01Y1964567D02*
G03X494095Y1968504I-3937J0D01*
G01X498032Y1964567D02*
G03X494095Y1968504I-3937J0D01*
G01X501969Y39370D02*
X631890D01*
G01X501969D02*
G03X498032Y35433I0J-3937D01*
G01Y3937D02*
Y35433D01*
G01X505897Y0D02*
X648386D01*
G01X505897Y7615D02*
Y0D01*
G01X597244Y31496D02*
X505897D01*
G01Y7615D02*
G03X498023I-3937J0D01*
G01Y31496D02*
G03X505897I3937J0D01*
G01X501969Y39370D02*
X631890D01*
G01X501969D02*
G03X498032Y35433I0J-3937D01*
G01Y3937D02*
Y35433D01*
G01X505897Y0D02*
X620827D01*
G01X505897Y7615D02*
Y0D01*
G01X597244Y31496D02*
X505897D01*
G01Y7615D02*
G03X498023I-3937J0D01*
G01Y31496D02*
G03X505897I3937J0D01*
G01X498032Y1933071D02*
Y1960630D01*
G01Y1933071D02*
G03X501969Y1929134I3937J0D01*
G01X631890D02*
X501969D01*
G01X498032Y1933071D02*
Y1964567D01*
G01Y1933071D02*
G03X501969Y1929134I3937J0D01*
G01X631890D02*
X501969D01*
G01X505906Y1960630D02*
Y1968504D01*
G01D02*
X648386D01*
G01X597244Y1937008D02*
X505906D01*
G01X498032Y1960630D02*
G03X505906I3937J0D01*
G01Y1937008D02*
G03X498032I-3937J0D01*
G01X505906Y1960630D02*
Y1968504D01*
G01D02*
X620827D01*
G01X597244Y1937008D02*
X505906D01*
G01X498032Y1960630D02*
G03X505906I3937J0D01*
G01Y1937008D02*
G03X498032I-3937J0D01*
G01X575349Y-152763D02*
Y-135263D01*
X572729Y-138763D01*
G01Y-152763D02*
X577969D01*
G01X588701Y-138180D02*
X590011Y-136430D01*
X591539Y-135555D01*
X593286Y-135263D01*
X595469Y-135846D01*
X596997Y-137305D01*
X597434Y-139054D01*
X597216Y-140805D01*
X596342Y-142263D01*
X591976Y-145180D01*
X590011Y-147221D01*
X588701Y-150139D01*
X588264Y-152763D01*
X597434D01*
G01X606419Y-153346D02*
X614279Y-135263D01*
G01X627849Y-152763D02*
Y-135263D01*
X625229Y-138763D01*
G01Y-152763D02*
X630469D01*
G01X645349D02*
Y-135263D01*
X642729Y-138763D01*
G01Y-152763D02*
X647969D01*
G01X658919Y-153346D02*
X666779Y-135263D01*
G01X676201Y-138180D02*
X677511Y-136430D01*
X679039Y-135555D01*
X680786Y-135263D01*
X682969Y-135846D01*
X684497Y-137305D01*
X684934Y-139054D01*
X684716Y-140805D01*
X683842Y-142263D01*
X679476Y-145180D01*
X677511Y-147221D01*
X676201Y-150139D01*
X675764Y-152763D01*
X684934D01*
G01X697849Y-135263D02*
X696102Y-135846D01*
X694792Y-137305D01*
X693919Y-139054D01*
X693264Y-141388D01*
X693046Y-144013D01*
X693264Y-146638D01*
X693919Y-148972D01*
X694792Y-150722D01*
X696102Y-152180D01*
X697849Y-152763D01*
X699595Y-152180D01*
X700906Y-150722D01*
X701779Y-148972D01*
X702434Y-146638D01*
X702652Y-144013D01*
X702434Y-141388D01*
X701779Y-139054D01*
X700906Y-137305D01*
X699595Y-135846D01*
X697849Y-135263D01*
G01X715349Y-152763D02*
Y-135263D01*
X712729Y-138763D01*
G01Y-152763D02*
X717969D01*
G01X728046Y-150139D02*
X729355Y-151597D01*
X730884Y-152471D01*
X732849Y-152763D01*
X734814Y-152180D01*
X736342Y-151013D01*
X737434Y-148972D01*
X737652Y-146638D01*
X737216Y-144305D01*
X736124Y-142846D01*
X734595Y-141680D01*
X733067Y-141388D01*
X731539Y-141680D01*
X729574Y-142846D01*
X730229Y-135263D01*
X736124D01*
G01X623046Y-107763D02*
Y-90263D01*
X627412D01*
X629159Y-91138D01*
X630469Y-92305D01*
X631561Y-94054D01*
X632434Y-96097D01*
X632652Y-99013D01*
X632434Y-101930D01*
X631561Y-103972D01*
X630469Y-105722D01*
X629159Y-106888D01*
X627412Y-107763D01*
X623046D01*
G01X649279D02*
Y-96097D01*
G01Y-98138D02*
X648406Y-96972D01*
X647095Y-96388D01*
X645567Y-96097D01*
X644039Y-96680D01*
X642729Y-97846D01*
X641855Y-99596D01*
X641419Y-101930D01*
X641855Y-104263D01*
X642729Y-106013D01*
X644039Y-107180D01*
X645567Y-107763D01*
X647095Y-107471D01*
X648406Y-106597D01*
X649279Y-105430D01*
G01X662849Y-90263D02*
Y-107763D01*
G01X659792Y-96097D02*
X665906D01*
G01X677074Y-99888D02*
X684061D01*
X683406Y-97846D01*
X682314Y-96680D01*
X680786Y-96097D01*
X679257Y-96388D01*
X677947Y-97263D01*
X677074Y-99305D01*
X676637Y-101055D01*
Y-102805D01*
X677074Y-104555D01*
X678166Y-106305D01*
X679476Y-107471D01*
X681004Y-107763D01*
X682532Y-107180D01*
X684061Y-105430D01*
G01X643701Y169256D02*
Y39370D01*
G01X635827Y31496D02*
G03X643701Y39370I0J7874D01*
G01X650689Y19685D02*
G03I-6988J0D01*
G01X631890Y39370D02*
G03X635827Y43307I0J3937D01*
G01Y31496D02*
X627953D01*
G01X597244D02*
G03Y39370I0J3937D01*
G01X627953D02*
G03Y31496I0J-3937D01*
G01X650689Y19685D02*
G03I-6988J0D01*
G01X631890Y39370D02*
G03X635827Y43307I0J3937D01*
G01Y31496D02*
X627953D01*
G01X597244D02*
G03Y39370I0J3937D01*
G01X627953D02*
G03Y31496I0J-3937D01*
G01X635827Y161417D02*
Y43307D01*
G01X643701Y169256D02*
G03X635827I-3937J0D01*
G01X643701D02*
G03X635827I-3937J0D01*
G01Y161417D02*
Y1807087D01*
G01Y161417D02*
Y1807087D01*
G01X643701Y436186D02*
Y199965D01*
G01X635827D02*
G03X643701I3937J0D01*
G01X635827D02*
G03X643701I3937J0D01*
G01Y436186D02*
G03X635827I-3937J0D01*
G01X643701D02*
G03X635827I-3937J0D01*
G01X643701Y703115D02*
Y466894D01*
G01X635827D02*
G03X643701I3937J0D01*
G01X635827D02*
G03X643701I3937J0D01*
G01Y703115D02*
G03X635827I-3937J0D01*
G01X643701D02*
G03X635827I-3937J0D01*
G01X643701Y970832D02*
Y733823D01*
G01X635827D02*
G03X643701I3937J0D01*
G01X635827D02*
G03X643701I3937J0D01*
G01Y1234611D02*
Y997603D01*
G01X635827D02*
G03X643701I3937J0D01*
G01Y970832D02*
G03X635827I-3937J0D01*
G01Y997603D02*
G03X643701I3937J0D01*
G01Y970832D02*
G03X635827I-3937J0D01*
G01X643701Y1501541D02*
Y1265320D01*
G01X635827D02*
G03X643701I3937J0D01*
G01Y1234611D02*
G03X635827I-3937J0D01*
G01Y1265320D02*
G03X643701I3937J0D01*
G01Y1234611D02*
G03X635827I-3937J0D01*
G01X643701Y1501541D02*
G03X635827I-3937J0D01*
G01X643701D02*
G03X635827I-3937J0D01*
G01X643701Y1768470D02*
Y1532249D01*
G01X635827D02*
G03X643701I3937J0D01*
G01X635827D02*
G03X643701I3937J0D01*
G01Y1768470D02*
G03X635827I-3937J0D01*
G01X643701D02*
G03X635827I-3937J0D01*
G01Y1799178D02*
G03X643701I3937J0D01*
G01X635827D02*
G03X643701I3937J0D01*
G01Y1929134D02*
Y1799178D01*
G01X635827Y1818898D02*
Y1807087D01*
G01Y1818898D02*
Y1925197D01*
G01Y1818898D02*
Y1925197D01*
G01X643701Y1929134D02*
G03X635827Y1937008I-7874J0D01*
G01Y1925197D02*
G03X631890Y1929134I-3937J0D01*
G01X627953Y1937008D02*
G03Y1929134I0J-3937D01*
G01X597244D02*
G03Y1937008I0J3937D01*
G01X635827Y1925197D02*
G03X631890Y1929134I-3937J0D01*
G01X627953Y1937008D02*
G03Y1929134I0J-3937D01*
G01X597244D02*
G03Y1937008I0J3937D01*
G01X650689Y1948819D02*
G03I-6988J0D01*
G01X627953Y1937008D02*
X635827D01*
G01X650689Y1948819D02*
G03I-6988J0D01*
G01X627953Y1937008D02*
X635827D01*
G01X650689Y1948819D02*
G03I-6988J0D01*
G01X648386Y0D02*
G03X663386Y15000I0J15000D01*
G01Y1953504D02*
Y15000D01*
G01Y1953504D02*
G03X648386Y1968504I-15000J0D01*
G01X190000Y1193933D02*
X185000D01*
Y1196017D01*
X185250Y1196683D01*
X185583Y1197100D01*
X186250Y1197267D01*
X186917Y1197100D01*
X187333Y1196600D01*
X187583Y1196017D01*
Y1193933D01*
G01Y1196017D02*
X190000Y1197267D01*
G01Y1201200D02*
X189917Y1200533D01*
X189583Y1199950D01*
X189083Y1199450D01*
X188500Y1199117D01*
X187833Y1198950D01*
X187167D01*
X186500Y1199117D01*
X185917Y1199450D01*
X185417Y1199950D01*
X185083Y1200533D01*
X185000Y1201200D01*
X185083Y1201867D01*
X185417Y1202450D01*
X185917Y1202950D01*
X186500Y1203283D01*
X187167Y1203450D01*
X187833D01*
X188500Y1203283D01*
X189083Y1202950D01*
X189583Y1202450D01*
X189917Y1201867D01*
X190000Y1201200D01*
G01Y1205050D02*
X185000D01*
G01Y1208550D02*
X190000D01*
G01X187500D02*
Y1205050D01*
G01X189333Y1210650D02*
X189750Y1211317D01*
X190000Y1212067D01*
Y1212733D01*
X189750Y1213400D01*
X189333Y1213900D01*
X188750Y1214150D01*
X188167Y1213983D01*
X187667Y1213567D01*
X187333Y1212817D01*
X187167Y1211817D01*
X186833Y1211233D01*
X186250Y1210983D01*
X185667Y1211150D01*
X185250Y1211567D01*
X185000Y1212150D01*
Y1212733D01*
X185167Y1213317D01*
X185583Y1213817D01*
G01X185417Y1225433D02*
X185167Y1224933D01*
X185000Y1224350D01*
Y1223683D01*
X185250Y1222933D01*
X185667Y1222350D01*
X186167Y1221933D01*
X187000Y1221600D01*
X187750Y1221517D01*
X188500Y1221683D01*
X189000Y1221933D01*
X189500Y1222433D01*
X189833Y1223017D01*
X190000Y1223600D01*
Y1224183D01*
X189833Y1224767D01*
X189583Y1225267D01*
X189250Y1225683D01*
G01X190000Y1229200D02*
X189917Y1228700D01*
X189583Y1228200D01*
X189000Y1227867D01*
X188333Y1227700D01*
X187667Y1227867D01*
X187083Y1228200D01*
X186750Y1228700D01*
X186667Y1229200D01*
X186750Y1229700D01*
X187083Y1230200D01*
X187667Y1230533D01*
X188333Y1230617D01*
X189000Y1230533D01*
X189583Y1230200D01*
X189917Y1229700D01*
X190000Y1229200D01*
G01Y1232300D02*
X186667D01*
G01X187583D02*
X187167Y1232550D01*
X186833Y1232967D01*
X186667Y1233550D01*
X186833Y1234133D01*
X187167Y1234550D01*
X187583Y1234800D01*
X190000D01*
G01X187583D02*
X187167Y1235050D01*
X186833Y1235467D01*
X186667Y1236050D01*
X186833Y1236633D01*
X187167Y1237050D01*
X187667Y1237300D01*
X190000D01*
G01X191667Y1238900D02*
X186667D01*
G01X187417D02*
X187000Y1239317D01*
X186750Y1239733D01*
X186667Y1240400D01*
X186750Y1240983D01*
X187167Y1241567D01*
X187750Y1241817D01*
X188333Y1241900D01*
X188917Y1241817D01*
X189500Y1241567D01*
X189833Y1241067D01*
X190000Y1240400D01*
X189917Y1239817D01*
X189667Y1239233D01*
X189333Y1238900D01*
G01X190000Y1246000D02*
X185000D01*
G01X186667Y1251600D02*
X190000D01*
G01X185333D02*
X185250Y1251433D01*
X185083D01*
X185000Y1251600D01*
X185083Y1251767D01*
X185250D01*
X185333Y1251600D01*
G01X190000Y1258700D02*
X186667D01*
G01X187250D02*
X186917Y1258367D01*
X186750Y1257867D01*
X186667Y1257283D01*
X186833Y1256700D01*
X187167Y1256200D01*
X187667Y1255867D01*
X188333Y1255700D01*
X189000Y1255867D01*
X189500Y1256200D01*
X189833Y1256700D01*
X190000Y1257283D01*
X189917Y1257867D01*
X189667Y1258367D01*
X189333Y1258700D01*
G01X190000Y1261383D02*
X186667D01*
G01X187500D02*
X187083Y1261717D01*
X186750Y1262217D01*
X186667Y1262883D01*
X186750Y1263467D01*
X187083Y1263967D01*
X187667Y1264217D01*
X190000D01*
G01X187083Y1269733D02*
X186750Y1269150D01*
X186667Y1268650D01*
X186833Y1267983D01*
X187167Y1267483D01*
X187750Y1267150D01*
X188333Y1267067D01*
X188917Y1267150D01*
X189417Y1267483D01*
X189833Y1267983D01*
X190000Y1268650D01*
X189833Y1269233D01*
X189500Y1269733D01*
G01X187750Y1272750D02*
Y1275417D01*
X187167Y1275167D01*
X186833Y1274750D01*
X186667Y1274167D01*
X186750Y1273583D01*
X187000Y1273083D01*
X187583Y1272750D01*
X188083Y1272583D01*
X188583D01*
X189083Y1272750D01*
X189583Y1273167D01*
X189917Y1273667D01*
X190000Y1274250D01*
X189833Y1274833D01*
X189333Y1275417D01*
G01X183500Y1356250D02*
X183458Y1355917D01*
X183292Y1355625D01*
X183042Y1355375D01*
X182750Y1355208D01*
X182417Y1355125D01*
X182083D01*
X181750Y1355208D01*
X181458Y1355375D01*
X181208Y1355625D01*
X181042Y1355917D01*
X181000Y1356250D01*
X181042Y1356583D01*
X181208Y1356875D01*
X181458Y1357125D01*
X181750Y1357292D01*
X182083Y1357375D01*
X182417D01*
X182750Y1357292D01*
X183042Y1357125D01*
X183292Y1356875D01*
X183458Y1356583D01*
X183500Y1356250D01*
G01X181000Y1359350D02*
X183500D01*
G01X181000Y1358392D02*
Y1360308D01*
G01X183500Y1361617D02*
X181000D01*
Y1362617D01*
X181125Y1362950D01*
X181417Y1363200D01*
X181750Y1363283D01*
X182083Y1363200D01*
X182333Y1362992D01*
X182458Y1362617D01*
Y1361617D01*
G01X183000Y1367817D02*
X183250Y1368025D01*
X183417Y1368275D01*
X183500Y1368567D01*
X183417Y1368900D01*
X183250Y1369150D01*
X183000Y1369400D01*
X182667Y1369483D01*
X181000D01*
G01Y1370833D02*
X182792D01*
X183167Y1371000D01*
X183417Y1371333D01*
X183500Y1371750D01*
X183417Y1372167D01*
X183167Y1372500D01*
X182792Y1372667D01*
X181000D01*
G01X183500Y1373767D02*
X181000D01*
X183083Y1374850D01*
X181000Y1375933D01*
X183500D01*
G01Y1377117D02*
X181000D01*
Y1378117D01*
X181125Y1378450D01*
X181417Y1378700D01*
X181750Y1378783D01*
X182083Y1378700D01*
X182333Y1378492D01*
X182458Y1378117D01*
Y1377117D01*
G01X183500Y1381883D02*
Y1380217D01*
X181000D01*
Y1381883D01*
G01X182208Y1381217D02*
Y1380217D01*
G01X183500Y1383317D02*
X181000D01*
Y1384358D01*
X181125Y1384692D01*
X181292Y1384900D01*
X181625Y1384983D01*
X181958Y1384900D01*
X182167Y1384650D01*
X182292Y1384358D01*
Y1383317D01*
G01Y1384358D02*
X183500Y1384983D01*
G01X183167Y1389475D02*
X183375Y1389808D01*
X183500Y1390183D01*
Y1390517D01*
X183375Y1390850D01*
X183167Y1391100D01*
X182875Y1391225D01*
X182583Y1391142D01*
X182333Y1390933D01*
X182167Y1390558D01*
X182083Y1390058D01*
X181917Y1389767D01*
X181625Y1389642D01*
X181333Y1389725D01*
X181125Y1389933D01*
X181000Y1390225D01*
Y1390517D01*
X181083Y1390808D01*
X181292Y1391058D01*
G01X183500Y1394283D02*
Y1392617D01*
X181000D01*
Y1394283D01*
G01X182208Y1393617D02*
Y1392617D01*
G01X181000Y1396550D02*
X183500D01*
G01X181000Y1395592D02*
Y1397508D01*
G01Y1399650D02*
X183500D01*
G01X181000Y1398692D02*
Y1400608D01*
G01Y1402250D02*
Y1403250D01*
G01Y1402750D02*
X183500D01*
G01Y1402250D02*
Y1403250D01*
G01Y1404892D02*
X181000D01*
X183500Y1406808D01*
X181000D01*
G01X182250Y1409200D02*
Y1410033D01*
X183000D01*
X183250Y1409783D01*
X183417Y1409492D01*
X183500Y1409075D01*
X183417Y1408658D01*
X183250Y1408367D01*
X183000Y1408117D01*
X182708Y1407950D01*
X182375Y1407867D01*
X182083D01*
X181833Y1407950D01*
X181542Y1408117D01*
X181292Y1408367D01*
X181125Y1408617D01*
X181000Y1408950D01*
Y1409242D01*
X181083Y1409575D01*
X181250Y1409825D01*
G01X176500Y1367417D02*
X174000D01*
Y1368417D01*
X174125Y1368750D01*
X174417Y1369000D01*
X174750Y1369083D01*
X175083Y1369000D01*
X175333Y1368792D01*
X175458Y1368417D01*
Y1367417D01*
G01X176500Y1371350D02*
X174000D01*
X174500Y1370850D01*
G01X176500D02*
Y1371850D01*
G01Y1377917D02*
X174000D01*
Y1378917D01*
X174125Y1379250D01*
X174417Y1379500D01*
X174750Y1379583D01*
X175083Y1379500D01*
X175333Y1379292D01*
X175458Y1378917D01*
Y1377917D01*
G01X174417Y1381058D02*
X174167Y1381308D01*
X174042Y1381600D01*
X174000Y1381933D01*
X174083Y1382350D01*
X174292Y1382642D01*
X174542Y1382725D01*
X174792Y1382683D01*
X175000Y1382517D01*
X175417Y1381683D01*
X175708Y1381308D01*
X176125Y1381058D01*
X176500Y1380975D01*
Y1382725D01*
G01Y1387917D02*
X174000D01*
Y1388917D01*
X174125Y1389250D01*
X174417Y1389500D01*
X174750Y1389583D01*
X175083Y1389500D01*
X175333Y1389292D01*
X175458Y1388917D01*
Y1387917D01*
G01X176000Y1390933D02*
X176292Y1391183D01*
X176458Y1391517D01*
X176500Y1391892D01*
X176458Y1392225D01*
X176250Y1392558D01*
X176000Y1392767D01*
X175750Y1392808D01*
X175458Y1392725D01*
X175250Y1392433D01*
X175167Y1392142D01*
Y1391767D01*
G01Y1392142D02*
X175042Y1392392D01*
X174833Y1392600D01*
X174583Y1392683D01*
X174333Y1392600D01*
X174125Y1392392D01*
X174000Y1392017D01*
X174042Y1391642D01*
X174208Y1391267D01*
G01X199417Y1358458D02*
X199167Y1358708D01*
X199042Y1359000D01*
X199000Y1359333D01*
X199083Y1359750D01*
X199292Y1360042D01*
X199542Y1360125D01*
X199792Y1360083D01*
X200000Y1359917D01*
X200417Y1359083D01*
X200708Y1358708D01*
X201125Y1358458D01*
X201500Y1358375D01*
Y1360125D01*
G01X200667Y1361808D02*
Y1362892D01*
G01X201000Y1364533D02*
X201292Y1364783D01*
X201458Y1365117D01*
X201500Y1365492D01*
X201458Y1365825D01*
X201250Y1366158D01*
X201000Y1366367D01*
X200750Y1366408D01*
X200458Y1366325D01*
X200250Y1366033D01*
X200167Y1365742D01*
Y1365367D01*
G01Y1365742D02*
X200042Y1365992D01*
X199833Y1366200D01*
X199583Y1366283D01*
X199333Y1366200D01*
X199125Y1365992D01*
X199000Y1365617D01*
X199042Y1365242D01*
X199208Y1364867D01*
G01X201583Y1368550D02*
X201542Y1368467D01*
X201458D01*
X201417Y1368550D01*
X201458Y1368633D01*
X201542D01*
X201583Y1368550D01*
G01X200458D02*
X200417Y1368467D01*
X200333D01*
X200292Y1368550D01*
X200333Y1368633D01*
X200417D01*
X200458Y1368550D01*
G01X201500Y1373708D02*
X199000Y1374750D01*
X201500Y1375792D01*
G01X200625Y1375417D02*
Y1374083D01*
G01X199000Y1376933D02*
X200792D01*
X201167Y1377100D01*
X201417Y1377433D01*
X201500Y1377850D01*
X201417Y1378267D01*
X201167Y1378600D01*
X200792Y1378767D01*
X199000D01*
G01Y1380950D02*
X201500D01*
G01X199000Y1379992D02*
Y1381908D01*
G01X201500Y1384050D02*
X201458Y1383717D01*
X201292Y1383425D01*
X201042Y1383175D01*
X200750Y1383008D01*
X200417Y1382925D01*
X200083D01*
X199750Y1383008D01*
X199458Y1383175D01*
X199208Y1383425D01*
X199042Y1383717D01*
X199000Y1384050D01*
X199042Y1384383D01*
X199208Y1384675D01*
X199458Y1384925D01*
X199750Y1385092D01*
X200083Y1385175D01*
X200417D01*
X200750Y1385092D01*
X201042Y1384925D01*
X201292Y1384675D01*
X201458Y1384383D01*
X201500Y1384050D01*
G01Y1389417D02*
X199000D01*
Y1390458D01*
X199125Y1390792D01*
X199292Y1391000D01*
X199625Y1391083D01*
X199958Y1391000D01*
X200167Y1390750D01*
X200292Y1390458D01*
Y1389417D01*
G01Y1390458D02*
X201500Y1391083D01*
G01Y1394183D02*
Y1392517D01*
X199000D01*
Y1394183D01*
G01X200208Y1393517D02*
Y1392517D01*
G01X200667Y1395908D02*
Y1396992D01*
G01X199000Y1399550D02*
X201500D01*
G01X199000Y1398592D02*
Y1400508D01*
G01X201500Y1401817D02*
X199000D01*
Y1402858D01*
X199125Y1403192D01*
X199292Y1403400D01*
X199625Y1403483D01*
X199958Y1403400D01*
X200167Y1403150D01*
X200292Y1402858D01*
Y1401817D01*
G01Y1402858D02*
X201500Y1403483D01*
G01Y1405750D02*
X200375D01*
X199000Y1404917D01*
G01Y1406583D02*
X200375Y1405750D01*
G01X192000Y1359250D02*
X189500D01*
X190000Y1358750D01*
G01X192000D02*
Y1359750D01*
G01X191167Y1361808D02*
Y1362892D01*
G01X189917Y1364658D02*
X189667Y1364908D01*
X189542Y1365200D01*
X189500Y1365533D01*
X189583Y1365950D01*
X189792Y1366242D01*
X190042Y1366325D01*
X190292Y1366283D01*
X190500Y1366117D01*
X190917Y1365283D01*
X191208Y1364908D01*
X191625Y1364658D01*
X192000Y1364575D01*
Y1366325D01*
G01X192083Y1368550D02*
X192042Y1368467D01*
X191958D01*
X191917Y1368550D01*
X191958Y1368633D01*
X192042D01*
X192083Y1368550D01*
G01X190958D02*
X190917Y1368467D01*
X190833D01*
X190792Y1368550D01*
X190833Y1368633D01*
X190917D01*
X190958Y1368550D01*
G01X189500Y1373917D02*
X192000D01*
Y1375583D01*
G01Y1376808D02*
X189500Y1377850D01*
X192000Y1378892D01*
G01X191125Y1378517D02*
Y1377183D01*
G01X189500Y1380950D02*
X192000D01*
G01X189500Y1379992D02*
Y1381908D01*
G01X189708Y1384967D02*
X189583Y1384717D01*
X189500Y1384425D01*
Y1384092D01*
X189625Y1383717D01*
X189833Y1383425D01*
X190083Y1383217D01*
X190500Y1383050D01*
X190875Y1383008D01*
X191250Y1383092D01*
X191500Y1383217D01*
X191750Y1383467D01*
X191917Y1383758D01*
X192000Y1384050D01*
Y1384342D01*
X191917Y1384633D01*
X191792Y1384883D01*
X191625Y1385092D01*
G01X192000Y1386275D02*
X189500D01*
G01Y1388025D02*
X192000D01*
G01X190750D02*
Y1386275D01*
G01X192000Y1355417D02*
X189500D01*
Y1356417D01*
X189625Y1356750D01*
X189917Y1357000D01*
X190250Y1357083D01*
X190583Y1357000D01*
X190833Y1356792D01*
X190958Y1356417D01*
Y1355417D01*
G01X201500D02*
X199000D01*
Y1356417D01*
X199125Y1356750D01*
X199417Y1357000D01*
X199750Y1357083D01*
X200083Y1357000D01*
X200333Y1356792D01*
X200458Y1356417D01*
Y1355417D01*
G54D14*
G01X137500Y1183500D02*
X157500Y1188166D01*
X137500Y1193500D01*
X157500Y1198833D01*
X137500Y1203500D01*
G01X144167Y1214300D02*
X157500D01*
G01X138834D02*
X138500Y1213633D01*
X137833D01*
X137500Y1214300D01*
X137833Y1214967D01*
X138500D01*
X138834Y1214300D01*
G01X144167Y1226766D02*
X157500Y1230767D01*
X144167Y1235100D01*
X157500Y1239433D01*
X144167Y1243434D01*
G01X163500Y1248900D02*
X164166Y1250900D01*
X163500Y1253567D01*
X162167Y1255233D01*
X160500Y1256567D01*
X155167Y1258566D01*
X144167Y1262900D01*
G01Y1252233D02*
X155167Y1258566D01*
G01X157500Y1271033D02*
X144167D01*
G01X147500D02*
X145833Y1272367D01*
X144500Y1274367D01*
X144167Y1277034D01*
X144500Y1279366D01*
X145833Y1281367D01*
X148167Y1282367D01*
X157500D01*
G01Y1291833D02*
X144167D01*
G01X147500D02*
X145833Y1293167D01*
X144500Y1295167D01*
X144167Y1297834D01*
X144500Y1300166D01*
X145833Y1302167D01*
X148167Y1303167D01*
X157500D01*
M02*
